# T6G (Grand Teton) — schematic netlist excerpt (pin names and nets, part order shuffled) for the footprints in the layout excerpt that follows; sources: Cadence DE-HDL packaged netlist, KiCad conversion of 04192023_DAF0TMB3IC0_F0TG_MB_C_brd_V02_OCP.brd

C540  Q_CAP  0.1UF 10V 10% X7S  pkg C0201  page 279 : A = P0V9_CPU0_RT_2D ; B = GND
PR185  Q_RES  2.2 1% CHIP  pkg 0402LF  page 211 : A = PVDDCR_CPU0_P1_PVCC ; B = PVDDCR_CPU0_P1_VCC1
C6114  Q_CAP  0.1UF 25V 10% X7R  pkg 0402  page 179 : A = P1V2_CPU0_USB2_DVDD12 ; B = GND

(kicad_pcb
	(version 20260206)
	(generator "pcbnew")
	(generator_version "10.0")
	(general
		(thickness 1.6)
		(legacy_teardrops no)
	)
	(paper "A4")
	(title_block
		(title "04192023_DAF0TMB3IC0_F0TG_MB_C_brd_V02_OCP.brd")
		(comment 1 "Grand Teton / footprints 5298-5300 of 8354")
	)
	(layers
		(0 "F.Cu" signal "TOP")
		(4 "In1.Cu" signal "GND")
		(6 "In2.Cu" signal "IN1")
		(8 "In3.Cu" signal "GND1")
		(10 "In4.Cu" signal "IN2")
		(12 "In5.Cu" signal "GND2")
		(14 "In6.Cu" signal "IN3")
		(16 "In7.Cu" signal "GND3")
		(18 "In8.Cu" signal "VCC")
		(20 "In9.Cu" signal "VCC1")
		(22 "In10.Cu" signal "GND4")
		(24 "In11.Cu" signal "IN4")
		(26 "In12.Cu" signal "GND5")
		(28 "In13.Cu" signal "IN5")
		(30 "In14.Cu" signal "GND6")
		(32 "In15.Cu" signal "IN6")
		(34 "In16.Cu" signal "GND7")
		(2 "B.Cu" signal "BOTTOM")
		(9 "F.Adhes" user "F.Adhesive")
		(11 "B.Adhes" user "B.Adhesive")
		(13 "F.Paste" user "Package Geometry/Pastemask Top")
		(15 "B.Paste" user "Package Geometry/Pastemask Bottom")
		(5 "F.SilkS" user "Ref Des/Silkscreen Top")
		(7 "B.SilkS" user "Ref Des/Silkscreen Bottom")
		(1 "F.Mask" user "Board Geometry/Soldermask Top")
		(3 "B.Mask" user "Board Geometry/Soldermask Bottom")
		(17 "Dwgs.User" user "User.Drawings")
		(19 "Cmts.User" user "User.Comments")
		(21 "Eco1.User" user "User.Eco1")
		(23 "Eco2.User" user "User.Eco2")
		(25 "Edge.Cuts" user "Board Geometry/Outline")
		(27 "Margin" user)
		(31 "F.CrtYd" user "Package Geometry/Place Bound Top")
		(29 "B.CrtYd" user "Package Geometry/Place Bound Bottom")
		(35 "F.Fab" user "Ref Des/Assembly Top")
		(33 "B.Fab" user "Ref Des/Assembly Bottom")
	)
	(footprint ""
		(layer "B.Cu")
		(at 84.595462 -181.684676 90)
		(property "Reference" "PR185"
			(at 0 0 90)
			(layer "B.SilkS")
			(hide yes)
			(effects
				(font
					(size 1.27 1.27)
				)
				(justify mirror)
			)
		)
		(property "Value" ""
			(at 0 0 90)
			(layer "B.Fab")
			(effects
				(font
					(size 1.27 1.27)
				)
				(justify mirror)
			)
		)
		(duplicate_pad_numbers_are_jumpers no)
		(fp_line
			(start 0.7874 -0.4064)
			(end -0.7874 -0.4064)
			(stroke
				(width 0.1524)
				(type default)
			)
			(layer "B.SilkS")
		)
		(fp_line
			(start -0.7874 -0.4064)
			(end -0.7874 0.4064)
			(stroke
				(width 0.1524)
				(type default)
			)
			(layer "B.SilkS")
		)
		(fp_line
			(start 0.7874 0.4064)
			(end 0.7874 -0.4064)
			(stroke
				(width 0.1524)
				(type default)
			)
			(layer "B.SilkS")
		)
		(fp_line
			(start -0.7874 0.4064)
			(end 0.7874 0.4064)
			(stroke
				(width 0.1524)
				(type default)
			)
			(layer "B.SilkS")
		)
		(fp_line
			(start 0.67945 -0.305054)
			(end 0.12065 -0.305054)
			(stroke
				(width 0.1)
				(type default)
			)
			(layer "B.Fab")
		)
		(fp_line
			(start 0.12065 -0.305054)
			(end 0.12065 -0.2794)
			(stroke
				(width 0.1)
				(type default)
			)
			(layer "B.Fab")
		)
		(fp_line
			(start -0.12065 -0.3048)
			(end -0.67945 -0.3048)
			(stroke
				(width 0.1)
				(type default)
			)
			(layer "B.Fab")
		)
		(fp_line
			(start -0.67945 -0.3048)
			(end -0.67945 0.3048)
			(stroke
				(width 0.1)
				(type default)
			)
			(layer "B.Fab")
		)
		(fp_line
			(start 0.12065 -0.2794)
			(end -0.12065 -0.2794)
			(stroke
				(width 0.1)
				(type default)
			)
			(layer "B.Fab")
		)
		(fp_line
			(start -0.12065 -0.2794)
			(end -0.12065 -0.3048)
			(stroke
				(width 0.1)
				(type default)
			)
			(layer "B.Fab")
		)
		(fp_line
			(start 0.12065 0.2794)
			(end 0.12065 0.3048)
			(stroke
				(width 0.1)
				(type default)
			)
			(layer "B.Fab")
		)
		(fp_line
			(start -0.120396 0.2794)
			(end 0.12065 0.2794)
			(stroke
				(width 0.1)
				(type default)
			)
			(layer "B.Fab")
		)
		(fp_line
			(start 0.67945 0.3048)
			(end 0.67945 -0.305054)
			(stroke
				(width 0.1)
				(type default)
			)
			(layer "B.Fab")
		)
		(fp_line
			(start 0.12065 0.3048)
			(end 0.67945 0.3048)
			(stroke
				(width 0.1)
				(type default)
			)
			(layer "B.Fab")
		)
		(fp_line
			(start -0.120396 0.3048)
			(end -0.120396 0.2794)
			(stroke
				(width 0.1)
				(type default)
			)
			(layer "B.Fab")
		)
		(fp_line
			(start -0.67945 0.3048)
			(end -0.120396 0.3048)
			(stroke
				(width 0.1)
				(type default)
			)
			(layer "B.Fab")
		)
		(pad "1" smd circle
			(at 0.40005 0 270)
			(size 0 0)
			(layers "B.Cu" "B.Mask" "B.Paste")
			(net "PVDDCR_CPU0_P1_PVCC")
		)
		(pad "2" smd circle
			(at -0.40005 0 270)
			(size 0 0)
			(layers "B.Cu" "B.Mask" "B.Paste")
			(net "PVDDCR_CPU0_P1_VCC1")
		)
	)
	(footprint ""
		(layer "B.Cu")
		(at 309.37835 -395.148562 90)
		(property "Reference" "C540"
			(at 0 0 90)
			(layer "B.SilkS")
			(hide yes)
			(effects
				(font
					(size 1.27 1.27)
				)
				(justify mirror)
			)
		)
		(property "Value" ""
			(at 0 0 90)
			(layer "B.Fab")
			(effects
				(font
					(size 1.27 1.27)
				)
				(justify mirror)
			)
		)
		(duplicate_pad_numbers_are_jumpers no)
		(fp_line
			(start 0.299974 -0.150114)
			(end -0.299974 -0.150114)
			(stroke
				(width 0.1)
				(type default)
			)
			(layer "B.Fab")
		)
		(fp_line
			(start -0.299974 -0.150114)
			(end -0.299974 0.150114)
			(stroke
				(width 0.1)
				(type default)
			)
			(layer "B.Fab")
		)
		(fp_line
			(start 0.299974 0.150114)
			(end 0.299974 -0.150114)
			(stroke
				(width 0.1)
				(type default)
			)
			(layer "B.Fab")
		)
		(fp_line
			(start -0.299974 0.150114)
			(end 0.299974 0.150114)
			(stroke
				(width 0.1)
				(type default)
			)
			(layer "B.Fab")
		)
		(pad "1" smd rect
			(at 0.2667 0 270)
			(size 0.3048 0.381)
			(layers "B.Cu" "B.Mask" "B.Paste")
			(net "P0V9_CPU0_RT_2D")
		)
		(pad "2" smd rect
			(at -0.2667 0 270)
			(size 0.3048 0.381)
			(layers "B.Cu" "B.Mask" "B.Paste")
			(net "GND")
		)
	)
	(footprint ""
		(layer "B.Cu")
		(at 109.49686 -35.088068 90)
		(property "Reference" "C6114"
			(at 0 0 90)
			(layer "B.SilkS")
			(hide yes)
			(effects
				(font
					(size 1.27 1.27)
				)
				(justify mirror)
			)
		)
		(property "Value" ""
			(at 0 0 90)
			(layer "B.Fab")
			(effects
				(font
					(size 1.27 1.27)
				)
				(justify mirror)
			)
		)
		(duplicate_pad_numbers_are_jumpers no)
		(fp_line
			(start 0.7874 -0.4064)
			(end -0.7874 -0.4064)
			(stroke
				(width 0.1524)
				(type default)
			)
			(layer "B.SilkS")
		)
		(fp_line
			(start -0.7874 -0.4064)
			(end -0.7874 0.4064)
			(stroke
				(width 0.1524)
				(type default)
			)
			(layer "B.SilkS")
		)
		(fp_line
			(start 0.7874 0.4064)
			(end 0.7874 -0.4064)
			(stroke
				(width 0.1524)
				(type default)
			)
			(layer "B.SilkS")
		)
		(fp_line
			(start -0.7874 0.4064)
			(end 0.7874 0.4064)
			(stroke
				(width 0.1524)
				(type default)
			)
			(layer "B.SilkS")
		)
		(fp_line
			(start 0.67945 -0.305054)
			(end 0.12065 -0.305054)
			(stroke
				(width 0.1)
				(type default)
			)
			(layer "B.Fab")
		)
		(fp_line
			(start 0.12065 -0.305054)
			(end 0.12065 -0.2794)
			(stroke
				(width 0.1)
				(type default)
			)
			(layer "B.Fab")
		)
		(fp_line
			(start -0.12065 -0.3048)
			(end -0.67945 -0.3048)
			(stroke
				(width 0.1)
				(type default)
			)
			(layer "B.Fab")
		)
		(fp_line
			(start -0.67945 -0.3048)
			(end -0.67945 0.3048)
			(stroke
				(width 0.1)
				(type default)
			)
			(layer "B.Fab")
		)
		(fp_line
			(start 0.12065 -0.2794)
			(end -0.12065 -0.2794)
			(stroke
				(width 0.1)
				(type default)
			)
			(layer "B.Fab")
		)
		(fp_line
			(start -0.12065 -0.2794)
			(end -0.12065 -0.3048)
			(stroke
				(width 0.1)
				(type default)
			)
			(layer "B.Fab")
		)
		(fp_line
			(start 0.12065 0.2794)
			(end 0.12065 0.3048)
			(stroke
				(width 0.1)
				(type default)
			)
			(layer "B.Fab")
		)
		(fp_line
			(start -0.120396 0.2794)
			(end 0.12065 0.2794)
			(stroke
				(width 0.1)
				(type default)
			)
			(layer "B.Fab")
		)
		(fp_line
			(start 0.67945 0.3048)
			(end 0.67945 -0.305054)
			(stroke
				(width 0.1)
				(type default)
			)
			(layer "B.Fab")
		)
		(fp_line
			(start 0.12065 0.3048)
			(end 0.67945 0.3048)
			(stroke
				(width 0.1)
				(type default)
			)
			(layer "B.Fab")
		)
		(fp_line
			(start -0.120396 0.3048)
			(end -0.120396 0.2794)
			(stroke
				(width 0.1)
				(type default)
			)
			(layer "B.Fab")
		)
		(fp_line
			(start -0.67945 0.3048)
			(end -0.120396 0.3048)
			(stroke
				(width 0.1)
				(type default)
			)
			(layer "B.Fab")
		)
		(pad "1" smd circle
			(at 0.40005 0 270)
			(size 0 0)
			(layers "B.Cu" "B.Mask" "B.Paste")
			(net "P1V2_CPU0_USB2_DVDD12")
		)
		(pad "2" smd circle
			(at -0.40005 0 270)
			(size 0 0)
			(layers "B.Cu" "B.Mask" "B.Paste")
			(net "GND")
		)
	)
)
